(kicad_pcb
	(version 20260206)
	(generator "pcbnew")
	(generator_version "10.0")
	(general
		(thickness 1.6)
		(legacy_teardrops no)
	)
	(paper "A4")
	(title_block
		(title "01162023_DA0F0TEBIF0_F0T_Expander_BD_F_brd_V02_OCP.brd")
		(comment 1 "Grand Teton / footprints 8432-8440 of 9728")
	)
	(layers
		(0 "F.Cu" signal "TOP")
		(4 "In1.Cu" signal "GND")
		(6 "In2.Cu" signal "VCC")
		(8 "In3.Cu" signal "VCC1")
		(10 "In4.Cu" signal "GND1")
		(12 "In5.Cu" signal "IN1")
		(14 "In6.Cu" signal "GND2")
		(16 "In7.Cu" signal "IN2")
		(18 "In8.Cu" signal "GND3")
		(20 "In9.Cu" signal "IN3")
		(22 "In10.Cu" signal "GND4")
		(24 "In11.Cu" signal "IN4")
		(26 "In12.Cu" signal "GND5")
		(28 "In13.Cu" signal "IN5")
		(30 "In14.Cu" signal "GND6")
		(32 "In15.Cu" signal "IN6")
		(34 "In16.Cu" signal "GND7")
		(2 "B.Cu" signal "BOTTOM")
		(9 "F.Adhes" user "F.Adhesive")
		(11 "B.Adhes" user "B.Adhesive")
		(13 "F.Paste" user "Package Geometry/Pastemask Top")
		(15 "B.Paste" user "Package Geometry/Pastemask Bottom")
		(5 "F.SilkS" user "Ref Des/Silkscreen Top")
		(7 "B.SilkS" user "Ref Des/Silkscreen Bottom")
		(1 "F.Mask" user "Board Geometry/Soldermask Top")
		(3 "B.Mask" user "Board Geometry/Soldermask Bottom")
		(17 "Dwgs.User" user "User.Drawings")
		(19 "Cmts.User" user "User.Comments")
		(21 "Eco1.User" user "User.Eco1")
		(23 "Eco2.User" user "User.Eco2")
		(25 "Edge.Cuts" user "Board Geometry/Outline")
		(27 "Margin" user)
		(31 "F.CrtYd" user "Package Geometry/Place Bound Top")
		(29 "B.CrtYd" user "Package Geometry/Place Bound Bottom")
		(35 "F.Fab" user "Ref Des/Assembly Top")
		(33 "B.Fab" user "Ref Des/Assembly Bottom")
	)
	(footprint ""
		(layer "B.Cu")
		(at 14.830298 -228.981)
		(property "Reference" "R3437"
			(at 0 0 0)
			(layer "B.SilkS")
			(hide yes)
			(effects
				(font
					(size 1.27 1.27)
				)
				(justify mirror)
			)
		)
		(property "Value" ""
			(at 0 0 0)
			(layer "B.Fab")
			(effects
				(font
					(size 1.27 1.27)
				)
				(justify mirror)
			)
		)
		(duplicate_pad_numbers_are_jumpers no)
		(fp_line
			(start -0.7874 -0.4064)
			(end -0.7874 0.4064)
			(stroke
				(width 0.1524)
				(type default)
			)
			(layer "B.SilkS")
		)
		(fp_line
			(start -0.7874 0.4064)
			(end 0.7874 0.4064)
			(stroke
				(width 0.1524)
				(type default)
			)
			(layer "B.SilkS")
		)
		(fp_line
			(start 0.7874 -0.4064)
			(end -0.7874 -0.4064)
			(stroke
				(width 0.1524)
				(type default)
			)
			(layer "B.SilkS")
		)
		(fp_line
			(start 0.7874 0.4064)
			(end 0.7874 -0.4064)
			(stroke
				(width 0.1524)
				(type default)
			)
			(layer "B.SilkS")
		)
		(fp_line
			(start -0.67945 -0.3048)
			(end -0.67945 0.3048)
			(stroke
				(width 0.1)
				(type default)
			)
			(layer "B.Fab")
		)
		(fp_line
			(start -0.67945 0.3048)
			(end -0.120396 0.3048)
			(stroke
				(width 0.1)
				(type default)
			)
			(layer "B.Fab")
		)
		(fp_line
			(start -0.12065 -0.3048)
			(end -0.67945 -0.3048)
			(stroke
				(width 0.1)
				(type default)
			)
			(layer "B.Fab")
		)
		(fp_line
			(start -0.12065 -0.2794)
			(end -0.12065 -0.3048)
			(stroke
				(width 0.1)
				(type default)
			)
			(layer "B.Fab")
		)
		(fp_line
			(start -0.120396 0.2794)
			(end 0.12065 0.2794)
			(stroke
				(width 0.1)
				(type default)
			)
			(layer "B.Fab")
		)
		(fp_line
			(start -0.120396 0.3048)
			(end -0.120396 0.2794)
			(stroke
				(width 0.1)
				(type default)
			)
			(layer "B.Fab")
		)
		(fp_line
			(start 0.12065 -0.305054)
			(end 0.12065 -0.2794)
			(stroke
				(width 0.1)
				(type default)
			)
			(layer "B.Fab")
		)
		(fp_line
			(start 0.12065 -0.2794)
			(end -0.12065 -0.2794)
			(stroke
				(width 0.1)
				(type default)
			)
			(layer "B.Fab")
		)
		(fp_line
			(start 0.12065 0.2794)
			(end 0.12065 0.3048)
			(stroke
				(width 0.1)
				(type default)
			)
			(layer "B.Fab")
		)
		(fp_line
			(start 0.12065 0.3048)
			(end 0.67945 0.3048)
			(stroke
				(width 0.1)
				(type default)
			)
			(layer "B.Fab")
		)
		(fp_line
			(start 0.67945 -0.305054)
			(end 0.12065 -0.305054)
			(stroke
				(width 0.1)
				(type default)
			)
			(layer "B.Fab")
		)
		(fp_line
			(start 0.67945 0.3048)
			(end 0.67945 -0.305054)
			(stroke
				(width 0.1)
				(type default)
			)
			(layer "B.Fab")
		)
		(pad "1" smd circle
			(at 0.40005 0 180)
			(size 0 0)
			(layers "B.Cu" "B.Mask" "B.Paste")
			(net "P1V8_PEX")
		)
		(pad "2" smd circle
			(at -0.40005 0 180)
			(size 0 0)
			(layers "B.Cu" "B.Mask" "B.Paste")
			(net "SPI_PEX0_SDIO2_R1")
		)
	)
	(footprint ""
		(layer "B.Cu")
		(at 284.724856 -297.79976 -90)
		(property "Reference" "C1647"
			(at 0 0 90)
			(layer "B.SilkS")
			(hide yes)
			(effects
				(font
					(size 1.27 1.27)
				)
				(justify mirror)
			)
		)
		(property "Value" ""
			(at 0 0 90)
			(layer "B.Fab")
			(effects
				(font
					(size 1.27 1.27)
				)
				(justify mirror)
			)
		)
		(duplicate_pad_numbers_are_jumpers no)
		(fp_line
			(start -0.299974 0.150114)
			(end 0.299974 0.150114)
			(stroke
				(width 0.1)
				(type default)
			)
			(layer "B.Fab")
		)
		(fp_line
			(start 0.299974 0.150114)
			(end 0.299974 -0.150114)
			(stroke
				(width 0.1)
				(type default)
			)
			(layer "B.Fab")
		)
		(fp_line
			(start -0.299974 -0.150114)
			(end -0.299974 0.150114)
			(stroke
				(width 0.1)
				(type default)
			)
			(layer "B.Fab")
		)
		(fp_line
			(start 0.299974 -0.150114)
			(end -0.299974 -0.150114)
			(stroke
				(width 0.1)
				(type default)
			)
			(layer "B.Fab")
		)
		(pad "1" smd rect
			(at 0.2667 0 90)
			(size 0.3048 0.381)
			(layers "B.Cu" "B.Mask" "B.Paste")
			(net "P0V8_PEX2")
		)
		(pad "2" smd rect
			(at -0.2667 0 90)
			(size 0.3048 0.381)
			(layers "B.Cu" "B.Mask" "B.Paste")
			(net "GND")
		)
	)
	(footprint ""
		(layer "B.Cu")
		(at 411.275022 -297.79976 -90)
		(property "Reference" "C1901"
			(at 0 0 90)
			(layer "B.SilkS")
			(hide yes)
			(effects
				(font
					(size 1.27 1.27)
				)
				(justify mirror)
			)
		)
		(property "Value" ""
			(at 0 0 90)
			(layer "B.Fab")
			(effects
				(font
					(size 1.27 1.27)
				)
				(justify mirror)
			)
		)
		(duplicate_pad_numbers_are_jumpers no)
		(fp_line
			(start -0.299974 0.150114)
			(end 0.299974 0.150114)
			(stroke
				(width 0.1)
				(type default)
			)
			(layer "B.Fab")
		)
		(fp_line
			(start 0.299974 0.150114)
			(end 0.299974 -0.150114)
			(stroke
				(width 0.1)
				(type default)
			)
			(layer "B.Fab")
		)
		(fp_line
			(start -0.299974 -0.150114)
			(end -0.299974 0.150114)
			(stroke
				(width 0.1)
				(type default)
			)
			(layer "B.Fab")
		)
		(fp_line
			(start 0.299974 -0.150114)
			(end -0.299974 -0.150114)
			(stroke
				(width 0.1)
				(type default)
			)
			(layer "B.Fab")
		)
		(pad "1" smd rect
			(at 0.2667 0 90)
			(size 0.3048 0.381)
			(layers "B.Cu" "B.Mask" "B.Paste")
			(net "P0V8_PEX3")
		)
		(pad "2" smd rect
			(at -0.2667 0 90)
			(size 0.3048 0.381)
			(layers "B.Cu" "B.Mask" "B.Paste")
			(net "GND")
		)
	)
	(footprint ""
		(layer "B.Cu")
		(at 60.599828 -288.299906 90)
		(property "Reference" "C2921"
			(at 0 0 90)
			(layer "B.SilkS")
			(hide yes)
			(effects
				(font
					(size 1.27 1.27)
				)
				(justify mirror)
			)
		)
		(property "Value" ""
			(at 0 0 90)
			(layer "B.Fab")
			(effects
				(font
					(size 1.27 1.27)
				)
				(justify mirror)
			)
		)
		(duplicate_pad_numbers_are_jumpers no)
		(fp_line
			(start 0.299974 -0.150114)
			(end -0.299974 -0.150114)
			(stroke
				(width 0.1)
				(type default)
			)
			(layer "B.Fab")
		)
		(fp_line
			(start -0.299974 -0.150114)
			(end -0.299974 0.150114)
			(stroke
				(width 0.1)
				(type default)
			)
			(layer "B.Fab")
		)
		(fp_line
			(start 0.299974 0.150114)
			(end 0.299974 -0.150114)
			(stroke
				(width 0.1)
				(type default)
			)
			(layer "B.Fab")
		)
		(fp_line
			(start -0.299974 0.150114)
			(end 0.299974 0.150114)
			(stroke
				(width 0.1)
				(type default)
			)
			(layer "B.Fab")
		)
		(pad "1" smd rect
			(at 0.2667 0 270)
			(size 0.3048 0.381)
			(layers "B.Cu" "B.Mask" "B.Paste")
			(net "P1V25_PEX0")
		)
		(pad "2" smd rect
			(at -0.2667 0 270)
			(size 0.3048 0.381)
			(layers "B.Cu" "B.Mask" "B.Paste")
			(net "GND")
		)
	)
	(footprint ""
		(layer "B.Cu")
		(at 297.549824 -303.499774 -90)
		(property "Reference" "C3250"
			(at 0 0 90)
			(layer "B.SilkS")
			(hide yes)
			(effects
				(font
					(size 1.27 1.27)
				)
				(justify mirror)
			)
		)
		(property "Value" ""
			(at 0 0 90)
			(layer "B.Fab")
			(effects
				(font
					(size 1.27 1.27)
				)
				(justify mirror)
			)
		)
		(duplicate_pad_numbers_are_jumpers no)
		(fp_line
			(start -0.299974 0.150114)
			(end 0.299974 0.150114)
			(stroke
				(width 0.1)
				(type default)
			)
			(layer "B.Fab")
		)
		(fp_line
			(start 0.299974 0.150114)
			(end 0.299974 -0.150114)
			(stroke
				(width 0.1)
				(type default)
			)
			(layer "B.Fab")
		)
		(fp_line
			(start -0.299974 -0.150114)
			(end -0.299974 0.150114)
			(stroke
				(width 0.1)
				(type default)
			)
			(layer "B.Fab")
		)
		(fp_line
			(start 0.299974 -0.150114)
			(end -0.299974 -0.150114)
			(stroke
				(width 0.1)
				(type default)
			)
			(layer "B.Fab")
		)
		(pad "1" smd rect
			(at 0.2667 0 90)
			(size 0.3048 0.381)
			(layers "B.Cu" "B.Mask" "B.Paste")
			(net "P1V25_PEX2")
		)
		(pad "2" smd rect
			(at -0.2667 0 90)
			(size 0.3048 0.381)
			(layers "B.Cu" "B.Mask" "B.Paste")
			(net "GND")
		)
	)
	(footprint ""
		(layer "B.Cu")
		(at 417.450016 -301.124874)
		(property "Reference" "C3515"
			(at 0 0 0)
			(layer "B.SilkS")
			(hide yes)
			(effects
				(font
					(size 1.27 1.27)
				)
				(justify mirror)
			)
		)
		(property "Value" ""
			(at 0 0 0)
			(layer "B.Fab")
			(effects
				(font
					(size 1.27 1.27)
				)
				(justify mirror)
			)
		)
		(duplicate_pad_numbers_are_jumpers no)
		(fp_line
			(start -0.299974 -0.150114)
			(end -0.299974 0.150114)
			(stroke
				(width 0.1)
				(type default)
			)
			(layer "B.Fab")
		)
		(fp_line
			(start -0.299974 0.150114)
			(end 0.299974 0.150114)
			(stroke
				(width 0.1)
				(type default)
			)
			(layer "B.Fab")
		)
		(fp_line
			(start 0.299974 -0.150114)
			(end -0.299974 -0.150114)
			(stroke
				(width 0.1)
				(type default)
			)
			(layer "B.Fab")
		)
		(fp_line
			(start 0.299974 0.150114)
			(end 0.299974 -0.150114)
			(stroke
				(width 0.1)
				(type default)
			)
			(layer "B.Fab")
		)
		(pad "1" smd rect
			(at 0.2667 0 180)
			(size 0.3048 0.381)
			(layers "B.Cu" "B.Mask" "B.Paste")
			(net "P1V8_PEX")
		)
		(pad "2" smd rect
			(at -0.2667 0 180)
			(size 0.3048 0.381)
			(layers "B.Cu" "B.Mask" "B.Paste")
			(net "GND")
		)
	)
	(footprint ""
		(layer "B.Cu")
		(at 252.011434 -355.160834 180)
		(property "Reference" "PR7164"
			(at 0 0 0)
			(layer "B.SilkS")
			(hide yes)
			(effects
				(font
					(size 1.27 1.27)
				)
				(justify mirror)
			)
		)
		(property "Value" ""
			(at 0 0 0)
			(layer "B.Fab")
			(effects
				(font
					(size 1.27 1.27)
				)
				(justify mirror)
			)
		)
		(duplicate_pad_numbers_are_jumpers no)
		(fp_line
			(start 0.7874 0.4064)
			(end 0.7874 -0.4064)
			(stroke
				(width 0.1524)
				(type default)
			)
			(layer "B.SilkS")
		)
		(fp_line
			(start 0.7874 -0.4064)
			(end -0.7874 -0.4064)
			(stroke
				(width 0.1524)
				(type default)
			)
			(layer "B.SilkS")
		)
		(fp_line
			(start -0.7874 0.4064)
			(end 0.7874 0.4064)
			(stroke
				(width 0.1524)
				(type default)
			)
			(layer "B.SilkS")
		)
		(fp_line
			(start -0.7874 -0.4064)
			(end -0.7874 0.4064)
			(stroke
				(width 0.1524)
				(type default)
			)
			(layer "B.SilkS")
		)
		(fp_line
			(start 0.67945 0.3048)
			(end 0.67945 -0.305054)
			(stroke
				(width 0.1)
				(type default)
			)
			(layer "B.Fab")
		)
		(fp_line
			(start 0.67945 -0.305054)
			(end 0.12065 -0.305054)
			(stroke
				(width 0.1)
				(type default)
			)
			(layer "B.Fab")
		)
		(fp_line
			(start 0.12065 0.3048)
			(end 0.67945 0.3048)
			(stroke
				(width 0.1)
				(type default)
			)
			(layer "B.Fab")
		)
		(fp_line
			(start 0.12065 0.2794)
			(end 0.12065 0.3048)
			(stroke
				(width 0.1)
				(type default)
			)
			(layer "B.Fab")
		)
		(fp_line
			(start 0.12065 -0.2794)
			(end -0.12065 -0.2794)
			(stroke
				(width 0.1)
				(type default)
			)
			(layer "B.Fab")
		)
		(fp_line
			(start 0.12065 -0.305054)
			(end 0.12065 -0.2794)
			(stroke
				(width 0.1)
				(type default)
			)
			(layer "B.Fab")
		)
		(fp_line
			(start -0.120396 0.3048)
			(end -0.120396 0.2794)
			(stroke
				(width 0.1)
				(type default)
			)
			(layer "B.Fab")
		)
		(fp_line
			(start -0.120396 0.2794)
			(end 0.12065 0.2794)
			(stroke
				(width 0.1)
				(type default)
			)
			(layer "B.Fab")
		)
		(fp_line
			(start -0.12065 -0.2794)
			(end -0.12065 -0.3048)
			(stroke
				(width 0.1)
				(type default)
			)
			(layer "B.Fab")
		)
		(fp_line
			(start -0.12065 -0.3048)
			(end -0.67945 -0.3048)
			(stroke
				(width 0.1)
				(type default)
			)
			(layer "B.Fab")
		)
		(fp_line
			(start -0.67945 0.3048)
			(end -0.120396 0.3048)
			(stroke
				(width 0.1)
				(type default)
			)
			(layer "B.Fab")
		)
		(fp_line
			(start -0.67945 -0.3048)
			(end -0.67945 0.3048)
			(stroke
				(width 0.1)
				(type default)
			)
			(layer "B.Fab")
		)
		(pad "1" smd circle
			(at 0.40005 0)
			(size 0 0)
			(layers "B.Cu" "B.Mask" "B.Paste")
			(net "IRQ_SML1_PMBUS_ALERT_N")
		)
		(pad "2" smd circle
			(at -0.40005 0)
			(size 0 0)
			(layers "B.Cu" "B.Mask" "B.Paste")
			(net "HSC_ALERT1_R_N")
		)
	)
	(footprint ""
		(layer "B.Cu")
		(at 131.52374 -282.263088 180)
		(property "Reference" "PR7169"
			(at 0 0 0)
			(layer "B.SilkS")
			(hide yes)
			(effects
				(font
					(size 1.27 1.27)
				)
				(justify mirror)
			)
		)
		(property "Value" ""
			(at 0 0 0)
			(layer "B.Fab")
			(effects
				(font
					(size 1.27 1.27)
				)
				(justify mirror)
			)
		)
		(duplicate_pad_numbers_are_jumpers no)
		(fp_line
			(start 0.7874 0.4064)
			(end 0.7874 -0.4064)
			(stroke
				(width 0.1524)
				(type default)
			)
			(layer "B.SilkS")
		)
		(fp_line
			(start 0.7874 -0.4064)
			(end -0.7874 -0.4064)
			(stroke
				(width 0.1524)
				(type default)
			)
			(layer "B.SilkS")
		)
		(fp_line
			(start -0.7874 0.4064)
			(end 0.7874 0.4064)
			(stroke
				(width 0.1524)
				(type default)
			)
			(layer "B.SilkS")
		)
		(fp_line
			(start -0.7874 -0.4064)
			(end -0.7874 0.4064)
			(stroke
				(width 0.1524)
				(type default)
			)
			(layer "B.SilkS")
		)
		(fp_line
			(start 0.67945 0.3048)
			(end 0.67945 -0.305054)
			(stroke
				(width 0.1)
				(type default)
			)
			(layer "B.Fab")
		)
		(fp_line
			(start 0.67945 -0.305054)
			(end 0.12065 -0.305054)
			(stroke
				(width 0.1)
				(type default)
			)
			(layer "B.Fab")
		)
		(fp_line
			(start 0.12065 0.3048)
			(end 0.67945 0.3048)
			(stroke
				(width 0.1)
				(type default)
			)
			(layer "B.Fab")
		)
		(fp_line
			(start 0.12065 0.2794)
			(end 0.12065 0.3048)
			(stroke
				(width 0.1)
				(type default)
			)
			(layer "B.Fab")
		)
		(fp_line
			(start 0.12065 -0.2794)
			(end -0.12065 -0.2794)
			(stroke
				(width 0.1)
				(type default)
			)
			(layer "B.Fab")
		)
		(fp_line
			(start 0.12065 -0.305054)
			(end 0.12065 -0.2794)
			(stroke
				(width 0.1)
				(type default)
			)
			(layer "B.Fab")
		)
		(fp_line
			(start -0.120396 0.3048)
			(end -0.120396 0.2794)
			(stroke
				(width 0.1)
				(type default)
			)
			(layer "B.Fab")
		)
		(fp_line
			(start -0.120396 0.2794)
			(end 0.12065 0.2794)
			(stroke
				(width 0.1)
				(type default)
			)
			(layer "B.Fab")
		)
		(fp_line
			(start -0.12065 -0.2794)
			(end -0.12065 -0.3048)
			(stroke
				(width 0.1)
				(type default)
			)
			(layer "B.Fab")
		)
		(fp_line
			(start -0.12065 -0.3048)
			(end -0.67945 -0.3048)
			(stroke
				(width 0.1)
				(type default)
			)
			(layer "B.Fab")
		)
		(fp_line
			(start -0.67945 0.3048)
			(end -0.120396 0.3048)
			(stroke
				(width 0.1)
				(type default)
			)
			(layer "B.Fab")
		)
		(fp_line
			(start -0.67945 -0.3048)
			(end -0.67945 0.3048)
			(stroke
				(width 0.1)
				(type default)
			)
			(layer "B.Fab")
		)
		(pad "1" smd circle
			(at 0.40005 0)
			(size 0 0)
			(layers "B.Cu" "B.Mask" "B.Paste")
			(net "P0V8_PEX0_EN4")
		)
		(pad "2" smd circle
			(at -0.40005 0)
			(size 0 0)
			(layers "B.Cu" "B.Mask" "B.Paste")
			(net "P0V8_PEX1_VCC2")
		)
	)
	(footprint ""
		(layer "B.Cu")
		(at 355.165406 -260.469126 90)
		(property "Reference" "PR7138"
			(at 0 0 90)
			(layer "B.SilkS")
			(hide yes)
			(effects
				(font
					(size 1.27 1.27)
				)
				(justify mirror)
			)
		)
		(property "Value" ""
			(at 0 0 90)
			(layer "B.Fab")
			(effects
				(font
					(size 1.27 1.27)
				)
				(justify mirror)
			)
		)
		(duplicate_pad_numbers_are_jumpers no)
		(fp_line
			(start 0.7874 -0.4064)
			(end -0.7874 -0.4064)
			(stroke
				(width 0.1524)
				(type default)
			)
			(layer "B.SilkS")
		)
		(fp_line
			(start -0.7874 -0.4064)
			(end -0.7874 0.4064)
			(stroke
				(width 0.1524)
				(type default)
			)
			(layer "B.SilkS")
		)
		(fp_line
			(start 0.7874 0.4064)
			(end 0.7874 -0.4064)
			(stroke
				(width 0.1524)
				(type default)
			)
			(layer "B.SilkS")
		)
		(fp_line
			(start -0.7874 0.4064)
			(end 0.7874 0.4064)
			(stroke
				(width 0.1524)
				(type default)
			)
			(layer "B.SilkS")
		)
		(fp_line
			(start 0.67945 -0.305054)
			(end 0.12065 -0.305054)
			(stroke
				(width 0.1)
				(type default)
			)
			(layer "B.Fab")
		)
		(fp_line
			(start 0.12065 -0.305054)
			(end 0.12065 -0.2794)
			(stroke
				(width 0.1)
				(type default)
			)
			(layer "B.Fab")
		)
		(fp_line
			(start -0.12065 -0.3048)
			(end -0.67945 -0.3048)
			(stroke
				(width 0.1)
				(type default)
			)
			(layer "B.Fab")
		)
		(fp_line
			(start -0.67945 -0.3048)
			(end -0.67945 0.3048)
			(stroke
				(width 0.1)
				(type default)
			)
			(layer "B.Fab")
		)
		(fp_line
			(start 0.12065 -0.2794)
			(end -0.12065 -0.2794)
			(stroke
				(width 0.1)
				(type default)
			)
			(layer "B.Fab")
		)
		(fp_line
			(start -0.12065 -0.2794)
			(end -0.12065 -0.3048)
			(stroke
				(width 0.1)
				(type default)
			)
			(layer "B.Fab")
		)
		(fp_line
			(start 0.12065 0.2794)
			(end 0.12065 0.3048)
			(stroke
				(width 0.1)
				(type default)
			)
			(layer "B.Fab")
		)
		(fp_line
			(start -0.120396 0.2794)
			(end 0.12065 0.2794)
			(stroke
				(width 0.1)
				(type default)
			)
			(layer "B.Fab")
		)
		(fp_line
			(start 0.67945 0.3048)
			(end 0.67945 -0.305054)
			(stroke
				(width 0.1)
				(type default)
			)
			(layer "B.Fab")
		)
		(fp_line
			(start 0.12065 0.3048)
			(end 0.67945 0.3048)
			(stroke
				(width 0.1)
				(type default)
			)
			(layer "B.Fab")
		)
		(fp_line
			(start -0.120396 0.3048)
			(end -0.120396 0.2794)
			(stroke
				(width 0.1)
				(type default)
			)
			(layer "B.Fab")
		)
		(fp_line
			(start -0.67945 0.3048)
			(end -0.120396 0.3048)
			(stroke
				(width 0.1)
				(type default)
			)
			(layer "B.Fab")
		)
		(pad "1" smd circle
			(at 0.40005 0 270)
			(size 0 0)
			(layers "B.Cu" "B.Mask" "B.Paste")
			(net "NC_P0V8_PEX2_ISEN4")
		)
		(pad "2" smd circle
			(at -0.40005 0 270)
			(size 0 0)
			(layers "B.Cu" "B.Mask" "B.Paste")
			(net "GND")
		)
	)
)
